(kicad_pcb
	(version 20241229)
	(generator "pcbnew")
	(generator_version "9.0")
	(general
		(thickness 1.599998)
		(legacy_teardrops no)
	)
	(paper "A4")
	(title_block
		(date "2023-02-12")
		(rev "1.1.5")
		(comment 9 "footprints 220-227 of 473")
	)
	(layers
		(0 "F.Cu" signal)
		(4 "In1.Cu" power "In1.GND")
		(6 "In2.Cu" signal)
		(8 "In3.Cu" power "In3.GND")
		(10 "In4.Cu" power "In4.VCC")
		(12 "In5.Cu" signal)
		(14 "In6.Cu" power "In6.VCC")
		(2 "B.Cu" signal)
		(9 "F.Adhes" user "F.Adhesive")
		(11 "B.Adhes" user "B.Adhesive")
		(13 "F.Paste" user)
		(15 "B.Paste" user)
		(5 "F.SilkS" user "F.Silkscreen")
		(7 "B.SilkS" user "B.Silkscreen")
		(1 "F.Mask" user)
		(3 "B.Mask" user)
		(17 "Dwgs.User" user "User.Drawings")
		(19 "Cmts.User" user "User.Comments")
		(21 "Eco1.User" user "User.Eco1")
		(23 "Eco2.User" user "User.Eco2")
		(25 "Edge.Cuts" user)
		(27 "Margin" user)
		(31 "F.CrtYd" user "F.Courtyard")
		(29 "B.CrtYd" user "B.Courtyard")
		(35 "F.Fab" user)
		(33 "B.Fab" user)
	)
	(footprint "antmicro-footprints:C_0603_1608Metric"
		(layer "F.Cu")
		(at 120.8 53.475 90)
		(descr "Capacitor SMD 0603")
		(tags "capacitor 0603")
		(property "Reference" "C187"
			(at 1.075 0.3 90)
			(layer "F.SilkS")
			(effects
				(font
					(size 0.7 0.7)
					(thickness 0.15)
				)
				(justify left bottom)
			)
		)
		(property "Value" "C_10u_25V_0603"
			(at 0 1.6 90)
			(layer "F.Fab")
			(effects
				(font
					(size 0.7 0.7)
					(thickness 0.15)
				)
				(justify left bottom)
			)
		)
		(property "Description" " "
			(at 0 0 90)
			(layer "F.Fab")
			(hide yes)
			(effects
				(font
					(size 1.27 1.27)
					(thickness 0.15)
				)
			)
		)
		(property "Author" "Antmicro"
			(at 174.275 -67.325 0)
			(layer "F.Fab")
			(hide yes)
			(effects
				(font
					(size 1 1)
					(thickness 0.15)
				)
			)
		)
		(property "Dielectric" ""
			(at 174.275 -67.325 0)
			(layer "F.Fab")
			(hide yes)
			(effects
				(font
					(size 1 1)
					(thickness 0.15)
				)
			)
		)
		(property "License" "Apache-2.0"
			(at 174.275 -67.325 0)
			(layer "F.Fab")
			(hide yes)
			(effects
				(font
					(size 1 1)
					(thickness 0.15)
				)
			)
		)
		(property "MPN" "C1608X5R1E106M080AC"
			(at 174.275 -67.325 0)
			(layer "F.Fab")
			(hide yes)
			(effects
				(font
					(size 1 1)
					(thickness 0.15)
				)
			)
		)
		(property "Manufacturer" "TDK"
			(at 174.275 -67.325 0)
			(layer "F.Fab")
			(hide yes)
			(effects
				(font
					(size 1 1)
					(thickness 0.15)
				)
			)
		)
		(property "Val" "10u/25V"
			(at 174.275 -67.325 0)
			(layer "F.Fab")
			(hide yes)
			(effects
				(font
					(size 1 1)
					(thickness 0.15)
				)
			)
		)
		(property "Voltage" ""
			(at 174.275 -67.325 0)
			(layer "F.Fab")
			(hide yes)
			(effects
				(font
					(size 1 1)
					(thickness 0.15)
				)
			)
		)
		(sheetname "Supply")
		(sheetfile "supply.kicad_sch")
		(attr exclude_from_pos_files exclude_from_bom dnp)
		(fp_line
			(start -0.3 -0.3)
			(end 0.3 -0.3)
			(stroke
				(width 0.15)
				(type solid)
			)
			(layer "F.SilkS")
		)
		(fp_line
			(start -0.3 0.3)
			(end 0.3 0.3)
			(stroke
				(width 0.15)
				(type solid)
			)
			(layer "F.SilkS")
		)
		(fp_rect
			(start -1.24 -0.7)
			(end 1.24 0.7)
			(stroke
				(width 0.05)
				(type solid)
			)
			(fill no)
			(layer "F.CrtYd")
		)
		(fp_rect
			(start -0.8 -0.4)
			(end 0.8 0.4)
			(stroke
				(width 0.15)
				(type solid)
			)
			(fill no)
			(layer "F.Fab")
		)
		(pad "1" smd roundrect
			(at -0.7 0 90)
			(size 0.6 0.8)
			(layers "F.Cu" "F.Mask" "F.Paste")
			(roundrect_rratio 0.2)
			(net 224 "VIN")
			(pintype "passive")
		)
		(pad "2" smd roundrect
			(at 0.7 0 90)
			(size 0.6 0.8)
			(layers "F.Cu" "F.Mask" "F.Paste")
			(roundrect_rratio 0.2)
			(net 5 "GND")
			(pintype "passive")
		)
	)
	(footprint "antmicro-footprints:TP_SMD_1mm"
		(layer "F.Cu")
		(at 146.1 109.099 180)
		(property "Reference" "TP1"
			(at -0.4 0.499 90)
			(layer "F.SilkS")
			(effects
				(font
					(size 0.7 0.7)
					(thickness 0.15)
				)
				(justify left bottom)
			)
		)
		(property "Value" "TP_1mm_SMD"
			(at 0 1.4 180)
			(layer "F.Fab")
			(effects
				(font
					(size 0.7 0.7)
					(thickness 0.15)
				)
				(justify left bottom)
			)
		)
		(property "Description" "Test Point 1mm"
			(at 0 0 180)
			(layer "F.Fab")
			(hide yes)
			(effects
				(font
					(size 1.27 1.27)
					(thickness 0.15)
				)
			)
		)
		(property "Author" "Antmicro"
			(at 292.2 218.198 0)
			(layer "F.Fab")
			(hide yes)
			(effects
				(font
					(size 1 1)
					(thickness 0.15)
				)
			)
		)
		(property "License" "Apache-2.0"
			(at 292.2 218.198 0)
			(layer "F.Fab")
			(hide yes)
			(effects
				(font
					(size 1 1)
					(thickness 0.15)
				)
			)
		)
		(property "MPN" ""
			(at 292.2 218.198 0)
			(layer "F.Fab")
			(hide yes)
			(effects
				(font
					(size 1 1)
					(thickness 0.15)
				)
			)
		)
		(property "Manufacturer" ""
			(at 292.2 218.198 0)
			(layer "F.Fab")
			(hide yes)
			(effects
				(font
					(size 1 1)
					(thickness 0.15)
				)
			)
		)
		(sheetname "Interfaces")
		(sheetfile "interfaces.kicad_sch")
		(attr exclude_from_pos_files)
		(pad "1" smd circle
			(at 0 0 180)
			(size 1 1)
			(layers "F.Cu" "F.Mask")
			(net 265 "Net-(U4-ADBUS5)")
			(pinfunction "1")
			(pintype "passive")
		)
	)
	(footprint "antmicro-footprints:C_0402_1005Metric"
		(layer "F.Cu")
		(at 138.8 61.2 -90)
		(descr "Capacitor SMD 0402")
		(tags "capacitor SMD 0402")
		(property "Reference" "C135"
			(at 1.1 -1.3 270)
			(layer "F.SilkS")
			(effects
				(font
					(size 0.7 0.7)
					(thickness 0.15)
				)
				(justify left bottom)
			)
		)
		(property "Value" "C_10u_0402"
			(at 0 1.4 270)
			(layer "F.Fab")
			(effects
				(font
					(size 0.7 0.7)
					(thickness 0.15)
				)
				(justify left bottom)
			)
		)
		(property "Description" " "
			(at 0 0 270)
			(layer "F.Fab")
			(hide yes)
			(effects
				(font
					(size 1.27 1.27)
					(thickness 0.15)
				)
			)
		)
		(property "Author" "Antmicro"
			(at 77.6 200 0)
			(layer "F.Fab")
			(hide yes)
			(effects
				(font
					(size 1 1)
					(thickness 0.15)
				)
			)
		)
		(property "Dielectric" ""
			(at 77.6 200 0)
			(layer "F.Fab")
			(hide yes)
			(effects
				(font
					(size 1 1)
					(thickness 0.15)
				)
			)
		)
		(property "License" "Apache-2.0"
			(at 77.6 200 0)
			(layer "F.Fab")
			(hide yes)
			(effects
				(font
					(size 1 1)
					(thickness 0.15)
				)
			)
		)
		(property "MPN" "CC0402MRX5R5BB106"
			(at 77.6 200 0)
			(layer "F.Fab")
			(hide yes)
			(effects
				(font
					(size 1 1)
					(thickness 0.15)
				)
			)
		)
		(property "Manufacturer" "Yaego"
			(at 77.6 200 0)
			(layer "F.Fab")
			(hide yes)
			(effects
				(font
					(size 1 1)
					(thickness 0.15)
				)
			)
		)
		(property "Val" "10u"
			(at 77.6 200 0)
			(layer "F.Fab")
			(hide yes)
			(effects
				(font
					(size 1 1)
					(thickness 0.15)
				)
			)
		)
		(property "Voltage" ""
			(at 77.6 200 0)
			(layer "F.Fab")
			(hide yes)
			(effects
				(font
					(size 1 1)
					(thickness 0.15)
				)
			)
		)
		(sheetname "Supply")
		(sheetfile "supply.kicad_sch")
		(attr smd)
		(fp_rect
			(start -0.94 -0.47)
			(end 0.94 0.47)
			(stroke
				(width 0.05)
				(type solid)
			)
			(fill no)
			(layer "F.CrtYd")
		)
		(fp_rect
			(start -0.499 -0.249)
			(end 0.499 0.249)
			(stroke
				(width 0.15)
				(type solid)
			)
			(fill no)
			(layer "F.Fab")
		)
		(pad "1" smd roundrect
			(at -0.484 0 270)
			(size 0.59 0.64)
			(layers "F.Cu" "F.Mask" "F.Paste")
			(roundrect_rratio 0.25)
			(net 461 "1V1_SYS")
			(pintype "passive")
		)
		(pad "2" smd roundrect
			(at 0.484 0 270)
			(size 0.59 0.64)
			(layers "F.Cu" "F.Mask" "F.Paste")
			(roundrect_rratio 0.25)
			(net 5 "GND")
			(pintype "passive")
		)
	)
	(footprint "antmicro-footprints:R_0402_1005Metric"
		(layer "F.Cu")
		(at 123.6475 102.449)
		(descr "Resistor SMD 0402")
		(tags "resistor SMD 0402")
		(property "Reference" "R142"
			(at -3.5475 0.351 0)
			(layer "F.SilkS")
			(effects
				(font
					(size 0.7 0.7)
					(thickness 0.15)
				)
				(justify left bottom)
			)
		)
		(property "Value" "R_31k6_0402"
			(at 0 1.4 0)
			(layer "F.Fab")
			(effects
				(font
					(size 0.7 0.7)
					(thickness 0.15)
				)
				(justify left bottom)
			)
		)
		(property "Description" "31k6 resistor in 0402 package with 1% tolerance"
			(at 0 0 0)
			(layer "F.Fab")
			(hide yes)
			(effects
				(font
					(size 1.27 1.27)
					(thickness 0.15)
				)
			)
		)
		(property "Author" "Antmicro"
			(at 0 0 0)
			(layer "F.Fab")
			(hide yes)
			(effects
				(font
					(size 1 1)
					(thickness 0.15)
				)
			)
		)
		(property "License" "Apache-2.0"
			(at 0 0 0)
			(layer "F.Fab")
			(hide yes)
			(effects
				(font
					(size 1 1)
					(thickness 0.15)
				)
			)
		)
		(property "MPN" "CR0402-FX-3162GLF"
			(at 0 0 0)
			(layer "F.Fab")
			(hide yes)
			(effects
				(font
					(size 1 1)
					(thickness 0.15)
				)
			)
		)
		(property "Manufacturer" "Bourns"
			(at 0 0 0)
			(layer "F.Fab")
			(hide yes)
			(effects
				(font
					(size 1 1)
					(thickness 0.15)
				)
			)
		)
		(property "Tolerance" "1%"
			(at 0 0 0)
			(layer "F.Fab")
			(hide yes)
			(effects
				(font
					(size 1 1)
					(thickness 0.15)
				)
			)
		)
		(property "Val" "31k6"
			(at 0 0 0)
			(layer "F.Fab")
			(hide yes)
			(effects
				(font
					(size 1 1)
					(thickness 0.15)
				)
			)
		)
		(sheetname "Supply")
		(sheetfile "supply.kicad_sch")
		(attr smd)
		(fp_rect
			(start -0.93 -0.47)
			(end 0.93 0.47)
			(stroke
				(width 0.05)
				(type solid)
			)
			(fill no)
			(layer "F.CrtYd")
		)
		(fp_rect
			(start -0.5 -0.25)
			(end 0.5 0.25)
			(stroke
				(width 0.15)
				(type solid)
			)
			(fill no)
			(layer "F.Fab")
		)
		(pad "1" smd roundrect
			(at -0.485 0)
			(size 0.59 0.64)
			(layers "F.Cu" "F.Mask" "F.Paste")
			(roundrect_rratio 0.25)
			(net 588 "/Supply/1V0_REG")
			(pintype "passive")
		)
		(pad "2" smd roundrect
			(at 0.485 0)
			(size 0.59 0.64)
			(layers "F.Cu" "F.Mask" "F.Paste")
			(roundrect_rratio 0.25)
			(net 599 "/Supply/1V0_FB")
			(pintype "passive")
		)
	)
	(footprint "antmicro-footprints:R_0402_1005Metric"
		(layer "F.Cu")
		(at 123.65 90.974)
		(descr "Resistor SMD 0402")
		(tags "resistor SMD 0402")
		(property "Reference" "R138"
			(at -3.65 0.326 0)
			(layer "F.SilkS")
			(effects
				(font
					(size 0.7 0.7)
					(thickness 0.15)
				)
				(justify left bottom)
			)
		)
		(property "Value" "R_31k6_0402"
			(at 0 1.4 0)
			(layer "F.Fab")
			(effects
				(font
					(size 0.7 0.7)
					(thickness 0.15)
				)
				(justify left bottom)
			)
		)
		(property "Description" "31k6 resistor in 0402 package with 1% tolerance"
			(at 0 0 0)
			(layer "F.Fab")
			(hide yes)
			(effects
				(font
					(size 1.27 1.27)
					(thickness 0.15)
				)
			)
		)
		(property "Author" "Antmicro"
			(at 0 0 0)
			(layer "F.Fab")
			(hide yes)
			(effects
				(font
					(size 1 1)
					(thickness 0.15)
				)
			)
		)
		(property "License" "Apache-2.0"
			(at 0 0 0)
			(layer "F.Fab")
			(hide yes)
			(effects
				(font
					(size 1 1)
					(thickness 0.15)
				)
			)
		)
		(property "MPN" "CR0402-FX-3162GLF"
			(at 0 0 0)
			(layer "F.Fab")
			(hide yes)
			(effects
				(font
					(size 1 1)
					(thickness 0.15)
				)
			)
		)
		(property "Manufacturer" "Bourns"
			(at 0 0 0)
			(layer "F.Fab")
			(hide yes)
			(effects
				(font
					(size 1 1)
					(thickness 0.15)
				)
			)
		)
		(property "Tolerance" "1%"
			(at 0 0 0)
			(layer "F.Fab")
			(hide yes)
			(effects
				(font
					(size 1 1)
					(thickness 0.15)
				)
			)
		)
		(property "Val" "31k6"
			(at 0 0 0)
			(layer "F.Fab")
			(hide yes)
			(effects
				(font
					(size 1 1)
					(thickness 0.15)
				)
			)
		)
		(sheetname "Supply")
		(sheetfile "supply.kicad_sch")
		(attr smd)
		(fp_rect
			(start -0.93 -0.47)
			(end 0.93 0.47)
			(stroke
				(width 0.05)
				(type solid)
			)
			(fill no)
			(layer "F.CrtYd")
		)
		(fp_rect
			(start -0.5 -0.25)
			(end 0.5 0.25)
			(stroke
				(width 0.15)
				(type solid)
			)
			(fill no)
			(layer "F.Fab")
		)
		(pad "1" smd roundrect
			(at -0.485 0)
			(size 0.59 0.64)
			(layers "F.Cu" "F.Mask" "F.Paste")
			(roundrect_rratio 0.25)
			(net 587 "/Supply/1V1_REG")
			(pintype "passive")
		)
		(pad "2" smd roundrect
			(at 0.485 0)
			(size 0.59 0.64)
			(layers "F.Cu" "F.Mask" "F.Paste")
			(roundrect_rratio 0.25)
			(net 598 "/Supply/1V1_FB")
			(pintype "passive")
		)
	)
	(footprint "antmicro-footprints:C_0603_1608Metric"
		(layer "F.Cu")
		(at 122.3 53.475 90)
		(descr "Capacitor SMD 0603")
		(tags "capacitor 0603")
		(property "Reference" "C186"
			(at 1.075 0.3 90)
			(layer "F.SilkS")
			(effects
				(font
					(size 0.7 0.7)
					(thickness 0.15)
				)
				(justify left bottom)
			)
		)
		(property "Value" "C_10u_25V_0603"
			(at 0 1.6 90)
			(layer "F.Fab")
			(effects
				(font
					(size 0.7 0.7)
					(thickness 0.15)
				)
				(justify left bottom)
			)
		)
		(property "Description" " "
			(at 0 0 90)
			(layer "F.Fab")
			(hide yes)
			(effects
				(font
					(size 1.27 1.27)
					(thickness 0.15)
				)
			)
		)
		(property "Author" "Antmicro"
			(at 175.775 -68.825 0)
			(layer "F.Fab")
			(hide yes)
			(effects
				(font
					(size 1 1)
					(thickness 0.15)
				)
			)
		)
		(property "Dielectric" ""
			(at 175.775 -68.825 0)
			(layer "F.Fab")
			(hide yes)
			(effects
				(font
					(size 1 1)
					(thickness 0.15)
				)
			)
		)
		(property "License" "Apache-2.0"
			(at 175.775 -68.825 0)
			(layer "F.Fab")
			(hide yes)
			(effects
				(font
					(size 1 1)
					(thickness 0.15)
				)
			)
		)
		(property "MPN" "C1608X5R1E106M080AC"
			(at 175.775 -68.825 0)
			(layer "F.Fab")
			(hide yes)
			(effects
				(font
					(size 1 1)
					(thickness 0.15)
				)
			)
		)
		(property "Manufacturer" "TDK"
			(at 175.775 -68.825 0)
			(layer "F.Fab")
			(hide yes)
			(effects
				(font
					(size 1 1)
					(thickness 0.15)
				)
			)
		)
		(property "Val" "10u/25V"
			(at 175.775 -68.825 0)
			(layer "F.Fab")
			(hide yes)
			(effects
				(font
					(size 1 1)
					(thickness 0.15)
				)
			)
		)
		(property "Voltage" ""
			(at 175.775 -68.825 0)
			(layer "F.Fab")
			(hide yes)
			(effects
				(font
					(size 1 1)
					(thickness 0.15)
				)
			)
		)
		(sheetname "Supply")
		(sheetfile "supply.kicad_sch")
		(attr exclude_from_pos_files exclude_from_bom dnp)
		(fp_line
			(start -0.3 -0.3)
			(end 0.3 -0.3)
			(stroke
				(width 0.15)
				(type solid)
			)
			(layer "F.SilkS")
		)
		(fp_line
			(start -0.3 0.3)
			(end 0.3 0.3)
			(stroke
				(width 0.15)
				(type solid)
			)
			(layer "F.SilkS")
		)
		(fp_rect
			(start -1.24 -0.7)
			(end 1.24 0.7)
			(stroke
				(width 0.05)
				(type solid)
			)
			(fill no)
			(layer "F.CrtYd")
		)
		(fp_rect
			(start -0.8 -0.4)
			(end 0.8 0.4)
			(stroke
				(width 0.15)
				(type solid)
			)
			(fill no)
			(layer "F.Fab")
		)
		(pad "1" smd roundrect
			(at -0.7 0 90)
			(size 0.6 0.8)
			(layers "F.Cu" "F.Mask" "F.Paste")
			(roundrect_rratio 0.2)
			(net 224 "VIN")
			(pintype "passive")
		)
		(pad "2" smd roundrect
			(at 0.7 0 90)
			(size 0.6 0.8)
			(layers "F.Cu" "F.Mask" "F.Paste")
			(roundrect_rratio 0.2)
			(net 5 "GND")
			(pintype "passive")
		)
	)
	(footprint "antmicro-footprints:C_0402_1005Metric"
		(layer "F.Cu")
		(at 111.147806 84.774 180)
		(descr "Capacitor SMD 0402")
		(tags "capacitor SMD 0402")
		(property "Reference" "C168"
			(at 3.647806 -0.326 180)
			(layer "F.SilkS")
			(effects
				(font
					(size 0.7 0.7)
					(thickness 0.15)
				)
				(justify left bottom)
			)
		)
		(property "Value" "C_22u_0402"
			(at 0 1.4 180)
			(layer "F.Fab")
			(effects
				(font
					(size 0.7 0.7)
					(thickness 0.15)
				)
				(justify left bottom)
			)
		)
		(property "Description" " "
			(at 0 0 180)
			(layer "F.Fab")
			(hide yes)
			(effects
				(font
					(size 1.27 1.27)
					(thickness 0.15)
				)
			)
		)
		(property "Author" "Antmicro"
			(at 222.295612 169.548 0)
			(layer "F.Fab")
			(hide yes)
			(effects
				(font
					(size 1 1)
					(thickness 0.15)
				)
			)
		)
		(property "Dielectric" ""
			(at 222.295612 169.548 0)
			(layer "F.Fab")
			(hide yes)
			(effects
				(font
					(size 1 1)
					(thickness 0.15)
				)
			)
		)
		(property "License" "Apache-2.0"
			(at 222.295612 169.548 0)
			(layer "F.Fab")
			(hide yes)
			(effects
				(font
					(size 1 1)
					(thickness 0.15)
				)
			)
		)
		(property "MPN" "04024W226MAT2A"
			(at 222.295612 169.548 0)
			(layer "F.Fab")
			(hide yes)
			(effects
				(font
					(size 1 1)
					(thickness 0.15)
				)
			)
		)
		(property "Manufacturer" "AVX"
			(at 222.295612 169.548 0)
			(layer "F.Fab")
			(hide yes)
			(effects
				(font
					(size 1 1)
					(thickness 0.15)
				)
			)
		)
		(property "Val" "22u"
			(at 222.295612 169.548 0)
			(layer "F.Fab")
			(hide yes)
			(effects
				(font
					(size 1 1)
					(thickness 0.15)
				)
			)
		)
		(property "Voltage" ""
			(at 222.295612 169.548 0)
			(layer "F.Fab")
			(hide yes)
			(effects
				(font
					(size 1 1)
					(thickness 0.15)
				)
			)
		)
		(sheetname "Supply")
		(sheetfile "supply.kicad_sch")
		(attr smd)
		(fp_rect
			(start -0.94 -0.47)
			(end 0.94 0.47)
			(stroke
				(width 0.05)
				(type solid)
			)
			(fill no)
			(layer "F.CrtYd")
		)
		(fp_rect
			(start -0.499 -0.249)
			(end 0.499 0.249)
			(stroke
				(width 0.15)
				(type solid)
			)
			(fill no)
			(layer "F.Fab")
		)
		(pad "1" smd roundrect
			(at -0.484 0 180)
			(size 0.59 0.64)
			(layers "F.Cu" "F.Mask" "F.Paste")
			(roundrect_rratio 0.25)
			(net 583 "/Supply/1V8_REG")
			(pintype "passive")
		)
		(pad "2" smd roundrect
			(at 0.484 0 180)
			(size 0.59 0.64)
			(layers "F.Cu" "F.Mask" "F.Paste")
			(roundrect_rratio 0.25)
			(net 5 "GND")
			(pintype "passive")
		)
	)
	(footprint "lpddr4-test-board-footprints:mounting-hole-3.2mm"
		(layer "F.Cu")
		(at 110.1 49.1)
		(property "Reference" "MH1"
			(at -0.178 4.025 0)
			(layer "F.SilkS")
			(hide yes)
			(effects
				(font
					(size 0.7 0.7)
					(thickness 0.15)
				)
				(justify left bottom)
			)
		)
		(property "Value" "M3.2"
			(at -0.153 -4.153 0)
			(layer "F.Fab")
			(hide yes)
			(effects
				(font
					(size 0.7 0.7)
					(thickness 0.15)
				)
				(justify left bottom)
			)
		)
		(attr through_hole board_only exclude_from_bom)
		(pad "1" thru_hole circle
			(at 0 0)
			(size 6 6)
			(drill 3.2)
			(layers "*.Cu" "*.Mask")
			(remove_unused_layers no)
		)
	)
)
